FILE_TYPE = CONNECTIVITY;
{Allegro Design Entry HDL 17.2-2016 S081 (4005846) 1/11/2022}
"PAGE_NUMBER" = 132;
0"NC";
1"GND\g";
2"GND\g";
3"P3V3_STBY\g";
4"PVDD18_S5_P0\g";
5"OCP_SFF_WAKE_BUFF_N";
6"M2_1_PEWAKE_N";
7"M2_2_PEWAKE_N";
8"IRQ_SLOT1_WAKE_N";
9"IRQ_SLOT2_WAKE_N";
10"IRQ_SLOT3_WAKE_N";
11"IRQ_LVC3_WAKE_N";
12"IRQ_LVC3_WAKE";
13"P3V3_STBY\g";
14"IRQ_WAKE_R_N";
15"IRQ_LVC3_WAKE";
16"IRQ_WAKE_N";
%"Q_RES"
"1","(-5225,3400)","0","pure_quanta","I12";
;
LOCATION"R1006"
$SEC"1"
CDS_SEC"1"
TOLERANCE"5%"
VALUE"33"
CDS_LIB"pure_quanta"
WATTAGE"1/16W"
MATERIAL"CHIP"
PART_NUMBER"CS03302JB29"
PACK_TYPE"0402LF";
"B"
$PN"2"11;
"A"
$PN"1"7;
%"Q_RES"
"1","(-5250,2525)","0","pure_quanta","I15";
;
LOCATION"R1002"
$SEC"1"
CDS_SEC"1"
TOLERANCE"5%"
VALUE"33"
CDS_LIB"pure_quanta"
WATTAGE"1/16W"
MATERIAL"CHIP"
PART_NUMBER"CS03302JB29"
PACK_TYPE"0402LF";
"B"
$PN"2"11;
"A"
$PN"1"8;
%"Q_RES"
"1","(-5250,2075)","0","pure_quanta","I17";
;
LOCATION"R1004"
$SEC"1"
CDS_SEC"1"
TOLERANCE"5%"
VALUE"33"
CDS_LIB"pure_quanta"
WATTAGE"1/16W"
MATERIAL"CHIP"
PART_NUMBER"CS03302JB29"
PACK_TYPE"0402LF";
"B"
$PN"2"11;
"A"
$PN"1"9;
%"Q_RES"
"1","(-5250,1575)","0","pure_quanta","I33";
;
LOCATION"R580"
$SEC"1"
CDS_SEC"1"
TOLERANCE"5%"
VALUE"33"
CDS_LIB"pure_quanta"
WATTAGE"1/16W"
MATERIAL"CHIP"
PART_NUMBER"CS03302JB29"
PACK_TYPE"0402LF";
"B"
$PN"2"11;
"A"
$PN"1"10;
%"UNIVERSAL_GND"
"1","(-2250,5100)","7","pure_quanta_power","I35";
;
CDS_LIB"pure_quanta_power"
HDL_POWER"GND";
"A"1;
%"MOSFET_DUAL_6P"
"1","(-1775,5050)","0","pure_quanta","I38";
;
LOCATION"Q4"
$SEC"1"
CDS_SEC"1"
PART_TYPE"SMLF"
MATERIAL"IC"
VALUE"2N7002KDW"
PART_NUMBER"BAM70020047"
CDS_LMAN_SYM_OUTLINE"-150,100,150,-100"
NEEDS_NO_SIZE"TRUE"
CDS_LIB"pure_quanta";
"D2"
$PN"3"14;
"D1"
$PN"6"12;
"S2"
$PN"4"2;
"S1"
$PN"1"1;
"G2"
$PN"5"15;
"G1"
$PN"2"11;
%"UNIVERSAL_GND"
"1","(-1375,5100)","1","pure_quanta_power","I42";
;
CDS_LIB"pure_quanta_power"
HDL_POWER"GND";
"A"2;
%"UNIVERSAL_POWER"
"1","(-3550,5525)","0","pure_quanta_power","I43";
;
HDL_POWER"P3V3_STBY"
CDS_LIB"pure_quanta_power";
"A"3;
%"Q_RES"
"2","(-3550,5275)","2","pure_quanta","I44";
;
LOCATION"R994"
$SEC"1"
CDS_SEC"1"
WATTAGE"1/16W"
MATERIAL"CHIP"
TOLERANCE"1%"
VALUE"10K"
PART_NUMBER"TMP_QCS31002FB26"
PACK_TYPE"0402LF"
CDS_LIB"pure_quanta";
"A"
$PN"1"3;
"B"
$PN"2"11;
%"UNIVERSAL_POWER"
"1","(-475,5450)","0","pure_quanta_power","I45";
;
HDL_POWER"PVDD18_S5_P0"
CDS_LIB"pure_quanta_power";
"A"4;
%"Q_RES"
"2","(-475,5250)","0","pure_quanta","I46";
;
LOCATION"R437"
$SEC"1"
CDS_SEC"1"
VALUE"2.2K"
PART_NUMBER"CS22202JB07"
PACK_TYPE"0402LF"
CDS_LIB"pure_quanta"
WATTAGE"1/16W"
MATERIAL"CHIP"
TOLERANCE"5%";
"A"
$PN"1"4;
"B"
$PN"2"16;
%"Q_RES"
"1","(-2375,4725)","2","pure_quanta","I48";
;
LOCATION"R1009"
$SEC"1"
CDS_SEC"1"
MATERIAL"CHIP"
VALUE"10K"
PACK_TYPE"0402LF"
CDS_LIB"pure_quanta"
WATTAGE"1/16W"
TOLERANCE"1%"
PART_NUMBER"TMP_QCS31002FB26";
"B"
$PN"2"12;
"A"
$PN"1"13;
%"UNIVERSAL_POWER"
"1","(-2025,4875)","0","pure_quanta_power","I49";
;
HDL_POWER"P3V3_STBY"
CDS_LIB"pure_quanta_power";
"A"13;
%"Q_RES"
"1","(-825,5000)","0","pure_quanta","I50";
;
LOCATION"R1311"
$SEC"1"
CDS_SEC"1"
TOLERANCE"5%"
VALUE"33"
CDS_LIB"pure_quanta"
WATTAGE"1/16W"
MATERIAL"CHIP"
PART_NUMBER"CS03302JB29"
PACK_TYPE"0402LF";
"B"
$PN"2"16;
"A"
$PN"1"14;
%"Q_RES"
"1","(-5225,4050)","0","pure_quanta","I8";
;
LOCATION"R116"
$SEC"1"
CDS_SEC"1"
WATTAGE"1/16W"
MATERIAL"CHIP"
TOLERANCE"5%"
VALUE"33"
PART_NUMBER"CS03302JB29"
PACK_TYPE"0402LF"
BOM_COST"PCH"
CDS_LIB"pure_quanta"
ROOM"PCH";
"B"
$PN"2"11;
"A"
$PN"1"5;
%"Q_RES"
"1","(-5225,3575)","0","pure_quanta","I9";
;
LOCATION"R1005"
$SEC"1"
CDS_SEC"1"
TOLERANCE"5%"
VALUE"33"
CDS_LIB"pure_quanta"
WATTAGE"1/16W"
MATERIAL"CHIP"
PART_NUMBER"CS03302JB29"
PACK_TYPE"0402LF";
"B"
$PN"2"11;
"A"
$PN"1"6;
END.
